FILE_TYPE = CONNECTIVITY;
{Allegro Design Entry HDL 17.4-2019 S026 (4007227) 1/17/2022}
"PAGE_NUMBER" = 328;
0"NC";
1"P5E_CPU1_P0_TX_BUF_C_DN<13>";
2"FM_GPU_PWRGD";
3"P5E_CPU1_P0_TX_BUF_C_DN<8>";
4"P5E_CPU1_P1_RX_BUF_DP<8>";
5"P5E_CPU1_P1_RX_BUF_DN<8>";
6"P5E_CPU1_P1_TX_BUF_C_DP<8>";
7"GND\g";
8"P5E_CPU1_P0_TX_BUF_C_DP<8>";
9"P5E_CPU1_P0_RX_BUF_DP<8>";
10"P5E_CPU1_P0_RX_BUF_DN<8>";
11"GPU_PEX_STRAP1";
12"GPU_PRSNT_N";
13"P5E_CPU1_P1_TX_BUF_C_DP<9>";
14"P5E_CPU1_P1_TX_BUF_C_DN<9>";
15"P5E_CPU1_P0_TX_BUF_C_DP<9>";
16"P5E_CPU1_P0_TX_BUF_C_DN<9>";
17"P5E_CPU1_P1_RX_BUF_DP<9>";
18"P5E_CPU1_P1_RX_BUF_DN<9>";
19"P5E_CPU1_P0_RX_BUF_DP<9>";
20"GND\g";
21"P5E_CPU1_P0_RX_BUF_DN<9>";
22"P5E_CPU1_P1_TX_BUF_C_DP<10>";
23"P5E_CPU1_P1_TX_BUF_C_DN<10>";
24"P5E_CPU1_P0_TX_BUF_C_DP<10>";
25"P5E_CPU1_P0_TX_BUF_C_DN<10>";
26"P5E_CPU1_P1_RX_BUF_DN<10>";
27"P5E_CPU1_P0_RX_BUF_DP<10>";
28"GPU_BASE_ID0";
29"FM_GPU_PWR_EN_R_BUF";
30"P5E_CPU1_P1_TX_BUF_C_DP<11>";
31"P5E_CPU1_P1_TX_BUF_C_DN<11>";
32"P5E_CPU1_P0_TX_BUF_C_DP<11>";
33"P5E_CPU1_P0_TX_BUF_C_DN<11>";
34"P5E_CPU1_P0_RX_BUF_DN<10>";
35"GPU_BASE_ID1";
36"GPU_FPGA_RST_R_BUF_N";
37"P5E_CPU1_P0_RX_BUF_DN<14>";
38"P5E_CPU1_P1_RX_BUF_DN<14>";
39"P5E_CPU1_P1_RX_BUF_DP<14>";
40"P5E_CPU1_P0_TX_BUF_C_DN<14>";
41"P5E_CPU1_P0_RX_BUF_DN<13>";
42"P5E_CPU1_P0_RX_BUF_DP<13>";
43"P5E_CPU1_P1_RX_BUF_DN<13>";
44"P5E_CPU1_P0_TX_BUF_C_DP<13>";
45"P5E_CPU1_P1_TX_BUF_C_DP<13>";
46"GPU_PEX_STRAP0";
47"P5E_CPU1_P0_RX_BUF_DN<12>";
48"P5E_CPU1_P1_TX_BUF_C_DP<12>";
49"P5E_CPU1_P1_TX_BUF_C_DN<12>";
50"P5E_CPU1_P0_TX_BUF_C_DP<12>";
51"P5E_CPU1_P1_RX_BUF_DP<12>";
52"P5E_CPU1_P1_TX_BUF_C_DN<13>";
53"P5E_CPU1_P1_RX_BUF_DP<13>";
54"P5E_CPU1_P1_TX_BUF_C_DP<14>";
55"P5E_CPU1_P0_TX_BUF_C_DP<14>";
56"P5E_CPU1_P0_RX_BUF_DP<14>";
57"P5E_CPU1_P1_TX_BUF_C_DP<15>";
58"P5E_CPU1_P1_TX_BUF_C_DN<15>";
59"P5E_CPU1_P0_TX_BUF_C_DP<15>";
60"P5E_CPU1_P0_TX_BUF_C_DN<15>";
61"P5E_CPU1_P1_RX_BUF_DN<15>";
62"P5E_CPU1_P1_RX_BUF_DP<15>";
63"P5E_CPU1_P1_RX_BUF_DP<10>";
64"P5E_CPU1_P1_TX_BUF_C_DN<8>";
65"P5E_CPU1_P1_TX_BUF_C_DN<14>";
66"P5E_CPU1_P0_RX_BUF_DN<11>";
67"P5E_CPU1_P0_RX_BUF_DP<11>";
68"P5E_CPU1_P1_RX_BUF_DP<11>";
69"P5E_CPU1_P1_RX_BUF_DN<11>";
70"P5E_CPU1_P0_RX_BUF_DP<12>";
71"P5E_CPU1_P1_RX_BUF_DN<12>";
72"P5E_CPU1_P0_TX_BUF_C_DN<12>";
73"P5E_CPU1_P0_RX_BUF_DP<15>";
74"P5E_CPU1_P0_RX_BUF_DN<15>";
%"UNIVERSAL_GND"
"1","(-1175,150)","0","pure_quanta_power","I1";
;
CDS_LIB"pure_quanta_power"
HDL_POWER"GND";
"A"20;
%"CONN112_10137002101LF"
"1","(-75,2050)","0","pure_quanta","I38";
;
LOCATION"J111"
$SEC"1"
CDS_SEC"1"
MATERIAL"IO"
PART_TYPE"THLF"
VALUE"CONN112_10137002-101LF"
CDS_LMAN_SYM_OUTLINE"-775,1650,775,-1650"
NEEDS_NO_SIZE"TRUE"
CDS_LIB"pure_quanta"
PART_NUMBER"DFHSB2FR012";
"N8"
$PN"N8"35;
"M8"
$PN"M8"20;
"N7"
$PN"N7"20;
"M7"
$PN"M7"54;
"N6"
$PN"N6"2;
"M6"
$PN"M6"20;
"N5"
$PN"N5"20;
"M5"
$PN"M5"48;
"L5"
$PN"L5"49;
"L6"
$PN"L6"45;
"L7"
$PN"L7"65;
"L8"
$PN"L8"57;
"K5"
$PN"K5"20;
"K6"
$PN"K6"52;
"K7"
$PN"K7"20;
"K8"
$PN"K8"58;
"J5"
$PN"J5"50;
"J6"
$PN"J6"20;
"J7"
$PN"J7"55;
"J8"
$PN"J8"20;
"I5"
$PN"I5"72;
"I6"
$PN"I6"44;
"I7"
$PN"I7"40;
"I8"
$PN"I8"59;
"H5"
$PN"H5"20;
"H6"
$PN"H6"1;
"H7"
$PN"H7"20;
"H8"
$PN"H8"60;
"G5"
$PN"G5"51;
"G6"
$PN"G6"20;
"G7"
$PN"G7"39;
"G8"
$PN"G8"20;
"F5"
$PN"F5"71;
"F6"
$PN"F6"53;
"F7"
$PN"F7"38;
"F8"
$PN"F8"62;
"E5"
$PN"E5"20;
"E6"
$PN"E6"43;
"E7"
$PN"E7"20;
"E8"
$PN"E8"61;
"D5"
$PN"D5"70;
"D6"
$PN"D6"20;
"D7"
$PN"D7"56;
"D8"
$PN"D8"20;
"C5"
$PN"C5"47;
"C6"
$PN"C6"42;
"C7"
$PN"C7"37;
"C8"
$PN"C8"73;
"B5"
$PN"B5"20;
"B6"
$PN"B6"41;
"B7"
$PN"B7"20;
"B8"
$PN"B8"74;
"A5"
$PN"A5"46;
"A6"
$PN"A6"20;
"A7"
$PN"A7"36;
"A8"
$PN"A8"20;
%"UNIVERSAL_GND"
"1","(3525,100)","0","pure_quanta_power","I39";
;
CDS_LIB"pure_quanta_power"
HDL_POWER"GND";
"A"7;
%"CONN112_10137002101LF"
"2","(4675,2050)","0","pure_quanta","I76";
;
LOCATION"J111"
$SEC"2"
CDS_SEC"2"
MATERIAL"IO"
PART_TYPE"THLF"
CDS_LMAN_SYM_OUTLINE"-775,1650,775,-1650"
NEEDS_NO_SIZE"TRUE"
CDS_LIB"pure_quanta"
VALUE"CONN112_10137002-101LF"
PART_NUMBER"DFHSB2FR012";
"N4"
$PN"N4"29;
"M4"
$PN"M4"7;
"N3"
$PN"N3"7;
"M3"
$PN"M3"22;
"N2"
$PN"N2"12;
"M2"
$PN"M2"7;
"N1"
$PN"N1"7;
"M1"
$PN"M1"6;
"L1"
$PN"L1"64;
"L2"
$PN"L2"13;
"L3"
$PN"L3"23;
"L4"
$PN"L4"30;
"K1"
$PN"K1"7;
"K2"
$PN"K2"14;
"K3"
$PN"K3"7;
"K4"
$PN"K4"31;
"J1"
$PN"J1"8;
"J2"
$PN"J2"7;
"J3"
$PN"J3"24;
"J4"
$PN"J4"7;
"I1"
$PN"I1"3;
"I2"
$PN"I2"15;
"I3"
$PN"I3"25;
"I4"
$PN"I4"32;
"H1"
$PN"H1"7;
"H2"
$PN"H2"16;
"H3"
$PN"H3"7;
"H4"
$PN"H4"33;
"G1"
$PN"G1"4;
"G2"
$PN"G2"7;
"G3"
$PN"G3"63;
"G4"
$PN"G4"7;
"F1"
$PN"F1"5;
"F2"
$PN"F2"17;
"F3"
$PN"F3"26;
"F4"
$PN"F4"68;
"E1"
$PN"E1"7;
"E2"
$PN"E2"18;
"E3"
$PN"E3"7;
"E4"
$PN"E4"69;
"D1"
$PN"D1"9;
"D2"
$PN"D2"7;
"D3"
$PN"D3"27;
"D4"
$PN"D4"7;
"C1"
$PN"C1"10;
"C2"
$PN"C2"19;
"C3"
$PN"C3"34;
"C4"
$PN"C4"67;
"B1"
$PN"B1"7;
"B2"
$PN"B2"21;
"B3"
$PN"B3"7;
"B4"
$PN"B4"66;
"A1"
$PN"A1"11;
"A2"
$PN"A2"7;
"A3"
$PN"A3"28;
"A4"
$PN"A4"7;
END.
